# BASEBOARD_FAB2 (Tioga Pass) — schematic netlist excerpt (pin names and nets, part order shuffled) for the footprints in the layout excerpt that follows; sources: Cadence DE-HDL packaged netlist, KiCad conversion of Wiwynn_Tioga_Pass_MB.brd

R9L1  RES  1.00K 1% CHIP  pkg 0402  page 100 : A = M_M_VREF ; B = GND
R8W11  RES  0.0 5% CHIP  pkg 0402  page 245 : A = JTAG_RISER_TCK ; B = JTAG_PLD_TCK_MUX
R8D44  RES  10.0K 1% CHIP  pkg 0402  page 133 : A = P3V3_STBY ; B = FM_CPU0_RC_EN

(kicad_pcb
	(version 20260206)
	(generator "pcbnew")
	(generator_version "10.0")
	(general
		(thickness 1.6)
		(legacy_teardrops no)
	)
	(paper "A4")
	(title_block
		(title "Wiwynn_Tioga_Pass_MB.brd")
		(comment 1 "Tioga Pass / footprints 4417-4419 of 4770")
	)
	(layers
		(0 "F.Cu" signal "TOP")
		(4 "In1.Cu" signal "L2GND")
		(6 "In2.Cu" signal "L3")
		(8 "In3.Cu" signal "L4GND")
		(10 "In4.Cu" signal "L5")
		(12 "In5.Cu" signal "L6GND")
		(14 "In6.Cu" signal "L7VCC")
		(16 "In7.Cu" signal "L8VCC")
		(18 "In8.Cu" signal "L9GND")
		(20 "In9.Cu" signal "L10")
		(22 "In10.Cu" signal "L11GND")
		(24 "In11.Cu" signal "L12")
		(26 "In12.Cu" signal "L13GND")
		(2 "B.Cu" signal "BOTTOM")
		(9 "F.Adhes" user "F.Adhesive")
		(11 "B.Adhes" user "B.Adhesive")
		(13 "F.Paste" user "Package Geometry/Pastemask Top")
		(15 "B.Paste" user "Package Geometry/Pastemask Bottom")
		(5 "F.SilkS" user "Ref Des/Silkscreen Top")
		(7 "B.SilkS" user "Ref Des/Silkscreen Bottom")
		(1 "F.Mask" user "Board Geometry/Soldermask Top")
		(3 "B.Mask" user "Board Geometry/Soldermask Bottom")
		(17 "Dwgs.User" user "User.Drawings")
		(19 "Cmts.User" user "User.Comments")
		(21 "Eco1.User" user "User.Eco1")
		(23 "Eco2.User" user "User.Eco2")
		(25 "Edge.Cuts" user "Board Geometry/Outline")
		(27 "Margin" user)
		(31 "F.CrtYd" user "Package Geometry/Place Bound Top")
		(29 "B.CrtYd" user "Package Geometry/Place Bound Bottom")
		(35 "F.Fab" user "Ref Des/Assembly Top")
		(33 "B.Fab" user "Ref Des/Assembly Bottom")
	)
	(footprint ""
		(layer "B.Cu")
		(at 359.1052 -4.2418 180)
		(property "Reference" "R8W11"
			(at 0.8382 -0.67818 180)
			(unlocked yes)
			(layer "B.SilkS")
			(effects
				(font
					(size 0.4064 0.254)
					(thickness 0.1524)
				)
				(justify left mirror)
			)
		)
		(property "Value" ""
			(at 0 0 0)
			(layer "B.Fab")
			(effects
				(font
					(size 1.27 1.27)
				)
				(justify mirror)
			)
		)
		(duplicate_pad_numbers_are_jumpers no)
		(fp_poly
			(pts
				(xy 0.2794 -0.1016) (xy -0.2794 -0.1016) (xy -0.2794 0.9906) (xy 0.2794 0.9906)
			)
			(stroke
				(width 0)
				(type default)
			)
			(fill no)
			(layer "B.CrtYd")
		)
		(fp_line
			(start 0.2794 0.9906)
			(end -0.2794 0.9906)
			(stroke
				(width 0.1)
				(type default)
			)
			(layer "B.Fab")
		)
		(fp_line
			(start 0.2794 -0.1016)
			(end 0.2794 0.9906)
			(stroke
				(width 0.1)
				(type default)
			)
			(layer "B.Fab")
		)
		(fp_line
			(start -0.2794 0.9906)
			(end -0.2794 -0.1016)
			(stroke
				(width 0.1)
				(type default)
			)
			(layer "B.Fab")
		)
		(fp_line
			(start -0.2794 -0.1016)
			(end 0.2794 -0.1016)
			(stroke
				(width 0.1)
				(type default)
			)
			(layer "B.Fab")
		)
		(pad "1" smd rect
			(at 0 0)
			(size 0.508 0.508)
			(layers "B.Cu" "B.Mask" "B.Paste")
			(net "JTAG_RISER_TCK")
		)
		(pad "2" smd rect
			(at 0 0.889)
			(size 0.508 0.508)
			(layers "B.Cu" "B.Mask" "B.Paste")
			(net "JTAG_PLD_TCK_MUX")
		)
		(zone
			(layer "B.Cu")
			(hatch none 0.5)
			(connect_pads
				(clearance 0)
			)
			(min_thickness 0.25)
			(keepout
				(tracks not_allowed)
				(vias allowed)
				(pads allowed)
				(copperpour not_allowed)
				(footprints allowed)
			)
			(placement
				(enabled no)
				(sheetname "")
			)
			(fill
				(thermal_gap 0.5)
				(thermal_bridge_width 0.5)
				(island_removal_mode 0)
			)
			(polygon
				(pts
					(xy 358.8512 -4.8768) (xy 359.3592 -4.8768) (xy 359.3592 -4.4958) (xy 358.8512 -4.4958)
				)
			)
		)
		(zone
			(layer "B.Cu")
			(hatch none 0.5)
			(connect_pads
				(clearance 0)
			)
			(min_thickness 0.25)
			(keepout
				(tracks allowed)
				(vias not_allowed)
				(pads allowed)
				(copperpour not_allowed)
				(footprints allowed)
			)
			(placement
				(enabled no)
				(sheetname "")
			)
			(fill
				(thermal_gap 0.5)
				(thermal_bridge_width 0.5)
				(island_removal_mode 0)
			)
			(polygon
				(pts
					(xy 358.8512 -4.4958) (xy 359.3592 -4.4958) (xy 359.3592 -4.8768) (xy 358.8512 -4.8768)
				)
			)
		)
	)
	(footprint ""
		(layer "B.Cu")
		(at 29.563568 -155.448)
		(property "Reference" "R9L1"
			(at 0 0 0)
			(layer "B.SilkS")
			(hide yes)
			(effects
				(font
					(size 1.27 1.27)
				)
				(justify mirror)
			)
		)
		(property "Value" ""
			(at 0 0 0)
			(layer "B.Fab")
			(effects
				(font
					(size 1.27 1.27)
				)
				(justify mirror)
			)
		)
		(duplicate_pad_numbers_are_jumpers no)
		(fp_poly
			(pts
				(xy 0.2794 -0.1016) (xy -0.2794 -0.1016) (xy -0.2794 0.9906) (xy 0.2794 0.9906)
			)
			(stroke
				(width 0)
				(type default)
			)
			(fill no)
			(layer "B.CrtYd")
		)
		(fp_line
			(start -0.2794 -0.1016)
			(end 0.2794 -0.1016)
			(stroke
				(width 0.1)
				(type default)
			)
			(layer "B.Fab")
		)
		(fp_line
			(start -0.2794 0.9906)
			(end -0.2794 -0.1016)
			(stroke
				(width 0.1)
				(type default)
			)
			(layer "B.Fab")
		)
		(fp_line
			(start 0.2794 -0.1016)
			(end 0.2794 0.9906)
			(stroke
				(width 0.1)
				(type default)
			)
			(layer "B.Fab")
		)
		(fp_line
			(start 0.2794 0.9906)
			(end -0.2794 0.9906)
			(stroke
				(width 0.1)
				(type default)
			)
			(layer "B.Fab")
		)
		(pad "1" smd rect
			(at 0 0 180)
			(size 0.508 0.508)
			(layers "B.Cu" "B.Mask" "B.Paste")
			(net "M_M_VREF")
		)
		(pad "2" smd rect
			(at 0 0.889 180)
			(size 0.508 0.508)
			(layers "B.Cu" "B.Mask" "B.Paste")
			(net "GND")
		)
		(zone
			(layer "B.Cu")
			(hatch none 0.5)
			(connect_pads
				(clearance 0)
			)
			(min_thickness 0.25)
			(keepout
				(tracks allowed)
				(vias not_allowed)
				(pads allowed)
				(copperpour not_allowed)
				(footprints allowed)
			)
			(placement
				(enabled no)
				(sheetname "")
			)
			(fill
				(thermal_gap 0.5)
				(thermal_bridge_width 0.5)
				(island_removal_mode 0)
			)
			(polygon
				(pts
					(xy 29.817568 -155.194) (xy 29.309568 -155.194) (xy 29.309568 -154.813) (xy 29.817568 -154.813)
				)
			)
		)
		(zone
			(layer "B.Cu")
			(hatch none 0.5)
			(connect_pads
				(clearance 0)
			)
			(min_thickness 0.25)
			(keepout
				(tracks not_allowed)
				(vias allowed)
				(pads allowed)
				(copperpour not_allowed)
				(footprints allowed)
			)
			(placement
				(enabled no)
				(sheetname "")
			)
			(fill
				(thermal_gap 0.5)
				(thermal_bridge_width 0.5)
				(island_removal_mode 0)
			)
			(polygon
				(pts
					(xy 29.817568 -154.813) (xy 29.309568 -154.813) (xy 29.309568 -155.194) (xy 29.817568 -155.194)
				)
			)
		)
	)
	(footprint ""
		(layer "B.Cu")
		(at 402.336 -87.3125 180)
		(property "Reference" "R8D44"
			(at 0.8382 -0.67818 180)
			(unlocked yes)
			(layer "B.SilkS")
			(effects
				(font
					(size 0.4064 0.254)
					(thickness 0.1524)
				)
				(justify left mirror)
			)
		)
		(property "Value" ""
			(at 0 0 0)
			(layer "B.Fab")
			(effects
				(font
					(size 1.27 1.27)
				)
				(justify mirror)
			)
		)
		(duplicate_pad_numbers_are_jumpers no)
		(fp_poly
			(pts
				(xy 0.2794 -0.1016) (xy -0.2794 -0.1016) (xy -0.2794 0.9906) (xy 0.2794 0.9906)
			)
			(stroke
				(width 0)
				(type default)
			)
			(fill no)
			(layer "B.CrtYd")
		)
		(fp_line
			(start 0.2794 0.9906)
			(end -0.2794 0.9906)
			(stroke
				(width 0.1)
				(type default)
			)
			(layer "B.Fab")
		)
		(fp_line
			(start 0.2794 -0.1016)
			(end 0.2794 0.9906)
			(stroke
				(width 0.1)
				(type default)
			)
			(layer "B.Fab")
		)
		(fp_line
			(start -0.2794 0.9906)
			(end -0.2794 -0.1016)
			(stroke
				(width 0.1)
				(type default)
			)
			(layer "B.Fab")
		)
		(fp_line
			(start -0.2794 -0.1016)
			(end 0.2794 -0.1016)
			(stroke
				(width 0.1)
				(type default)
			)
			(layer "B.Fab")
		)
		(pad "1" smd rect
			(at 0 0)
			(size 0.508 0.508)
			(layers "B.Cu" "B.Mask" "B.Paste")
			(net "P3V3_STBY")
		)
		(pad "2" smd rect
			(at 0 0.889)
			(size 0.508 0.508)
			(layers "B.Cu" "B.Mask" "B.Paste")
			(net "FM_CPU0_RC_EN")
		)
		(zone
			(layer "B.Cu")
			(hatch none 0.5)
			(connect_pads
				(clearance 0)
			)
			(min_thickness 0.25)
			(keepout
				(tracks not_allowed)
				(vias allowed)
				(pads allowed)
				(copperpour not_allowed)
				(footprints allowed)
			)
			(placement
				(enabled no)
				(sheetname "")
			)
			(fill
				(thermal_gap 0.5)
				(thermal_bridge_width 0.5)
				(island_removal_mode 0)
			)
			(polygon
				(pts
					(xy 402.082 -87.9475) (xy 402.59 -87.9475) (xy 402.59 -87.5665) (xy 402.082 -87.5665)
				)
			)
		)
		(zone
			(layer "B.Cu")
			(hatch none 0.5)
			(connect_pads
				(clearance 0)
			)
			(min_thickness 0.25)
			(keepout
				(tracks allowed)
				(vias not_allowed)
				(pads allowed)
				(copperpour not_allowed)
				(footprints allowed)
			)
			(placement
				(enabled no)
				(sheetname "")
			)
			(fill
				(thermal_gap 0.5)
				(thermal_bridge_width 0.5)
				(island_removal_mode 0)
			)
			(polygon
				(pts
					(xy 402.082 -87.5665) (xy 402.59 -87.5665) (xy 402.59 -87.9475) (xy 402.082 -87.9475)
				)
			)
		)
	)
)
